(kicad_pcb
	(version 20260206)
	(generator "pcbnew")
	(generator_version "10.0")
	(general
		(thickness 1.6)
		(legacy_teardrops no)
	)
	(paper "A4")
	(title_block
		(title "Wiwynn_Tioga_Pass_MB.brd")
		(comment 1 "Tioga Pass / footprints 1-7 of 4770")
	)
	(layers
		(0 "F.Cu" signal "TOP")
		(4 "In1.Cu" signal "L2GND")
		(6 "In2.Cu" signal "L3")
		(8 "In3.Cu" signal "L4GND")
		(10 "In4.Cu" signal "L5")
		(12 "In5.Cu" signal "L6GND")
		(14 "In6.Cu" signal "L7VCC")
		(16 "In7.Cu" signal "L8VCC")
		(18 "In8.Cu" signal "L9GND")
		(20 "In9.Cu" signal "L10")
		(22 "In10.Cu" signal "L11GND")
		(24 "In11.Cu" signal "L12")
		(26 "In12.Cu" signal "L13GND")
		(2 "B.Cu" signal "BOTTOM")
		(9 "F.Adhes" user "F.Adhesive")
		(11 "B.Adhes" user "B.Adhesive")
		(13 "F.Paste" user "Package Geometry/Pastemask Top")
		(15 "B.Paste" user "Package Geometry/Pastemask Bottom")
		(5 "F.SilkS" user "Ref Des/Silkscreen Top")
		(7 "B.SilkS" user "Ref Des/Silkscreen Bottom")
		(1 "F.Mask" user "Board Geometry/Soldermask Top")
		(3 "B.Mask" user "Board Geometry/Soldermask Bottom")
		(17 "Dwgs.User" user "User.Drawings")
		(19 "Cmts.User" user "User.Comments")
		(21 "Eco1.User" user "User.Eco1")
		(23 "Eco2.User" user "User.Eco2")
		(25 "Edge.Cuts" user "Board Geometry/Outline")
		(27 "Margin" user)
		(31 "F.CrtYd" user "Package Geometry/Place Bound Top")
		(29 "B.CrtYd" user "Package Geometry/Place Bound Bottom")
		(35 "F.Fab" user "Ref Des/Assembly Top")
		(33 "B.Fab" user "Ref Des/Assembly Bottom")
	)
	(footprint ""
		(layer "F.Cu")
		(at 22.225 -70.866)
		(property "Reference" "R1D43"
			(at 0 0 0)
			(layer "F.SilkS")
			(hide yes)
			(effects
				(font
					(size 1.27 1.27)
				)
			)
		)
		(property "Value" ""
			(at 0 0 0)
			(layer "F.Fab")
			(effects
				(font
					(size 1.27 1.27)
				)
			)
		)
		(duplicate_pad_numbers_are_jumpers no)
		(fp_poly
			(pts
				(xy -0.2794 -0.1016) (xy 0.2794 -0.1016) (xy 0.2794 0.9906) (xy -0.2794 0.9906)
			)
			(stroke
				(width 0)
				(type default)
			)
			(fill no)
			(layer "F.CrtYd")
		)
		(fp_line
			(start -0.2794 -0.1016)
			(end -0.2794 0.9906)
			(stroke
				(width 0.1)
				(type default)
			)
			(layer "F.Fab")
		)
		(fp_line
			(start -0.2794 0.9906)
			(end 0.2794 0.9906)
			(stroke
				(width 0.1)
				(type default)
			)
			(layer "F.Fab")
		)
		(fp_line
			(start 0.2794 -0.1016)
			(end -0.2794 -0.1016)
			(stroke
				(width 0.1)
				(type default)
			)
			(layer "F.Fab")
		)
		(fp_line
			(start 0.2794 0.9906)
			(end 0.2794 -0.1016)
			(stroke
				(width 0.1)
				(type default)
			)
			(layer "F.Fab")
		)
		(pad "1" smd rect
			(at 0 0)
			(size 0.508 0.508)
			(layers "F.Cu" "F.Mask" "F.Paste")
			(net "A_HSC_OV")
		)
		(pad "2" smd rect
			(at 0 0.889)
			(size 0.508 0.508)
			(layers "F.Cu" "F.Mask" "F.Paste")
			(net "AGND_HSC")
		)
		(zone
			(layer "F.Cu")
			(hatch none 0.5)
			(connect_pads
				(clearance 0)
			)
			(min_thickness 0.25)
			(keepout
				(tracks allowed)
				(vias not_allowed)
				(pads allowed)
				(copperpour not_allowed)
				(footprints allowed)
			)
			(placement
				(enabled no)
				(sheetname "")
			)
			(fill
				(thermal_gap 0.5)
				(thermal_bridge_width 0.5)
				(island_removal_mode 0)
			)
			(polygon
				(pts
					(xy 21.971 -70.612) (xy 22.479 -70.612) (xy 22.479 -70.231) (xy 21.971 -70.231)
				)
			)
		)
		(zone
			(layer "F.Cu")
			(hatch none 0.5)
			(connect_pads
				(clearance 0)
			)
			(min_thickness 0.25)
			(keepout
				(tracks not_allowed)
				(vias allowed)
				(pads allowed)
				(copperpour not_allowed)
				(footprints allowed)
			)
			(placement
				(enabled no)
				(sheetname "")
			)
			(fill
				(thermal_gap 0.5)
				(thermal_bridge_width 0.5)
				(island_removal_mode 0)
			)
			(polygon
				(pts
					(xy 21.971 -70.231) (xy 22.479 -70.231) (xy 22.479 -70.612) (xy 21.971 -70.612)
				)
			)
		)
	)
	(footprint ""
		(layer "F.Cu")
		(at 471.513916 -24.49322)
		(property "Reference" "EU8E1"
			(at -0.508 -1.49733 0)
			(unlocked yes)
			(layer "F.SilkS")
			(effects
				(font
					(size 0.7874 0.5842)
					(thickness 0.1524)
				)
			)
		)
		(property "Value" ""
			(at 0 0 0)
			(layer "F.Fab")
			(effects
				(font
					(size 1.27 1.27)
				)
			)
		)
		(duplicate_pad_numbers_are_jumpers no)
		(fp_line
			(start -0.747014 -0.78994)
			(end 2.853182 -0.78994)
			(stroke
				(width 0.1524)
				(type default)
			)
			(layer "F.SilkS")
		)
		(fp_line
			(start -0.747014 3.301492)
			(end -0.747014 -0.78994)
			(stroke
				(width 0.1524)
				(type default)
			)
			(layer "F.SilkS")
		)
		(fp_line
			(start 2.853182 -0.78994)
			(end 2.853182 3.301492)
			(stroke
				(width 0.1524)
				(type default)
			)
			(layer "F.SilkS")
		)
		(fp_circle
			(center -1.238504 -0.803148)
			(end -1.111504 -0.803148)
			(stroke
				(width 0.254)
				(type default)
			)
			(fill no)
			(layer "F.SilkS")
		)
		(fp_poly
			(pts
				(xy -0.747014 -0.78994) (xy -0.747014 4.310126) (xy 2.853182 4.310126) (xy 2.853182 -0.78994)
			)
			(stroke
				(width 0)
				(type default)
			)
			(fill no)
			(layer "F.CrtYd")
		)
		(fp_line
			(start -0.747014 -0.78994)
			(end 2.853182 -0.78994)
			(stroke
				(width 0.1)
				(type default)
			)
			(layer "F.Fab")
		)
		(fp_line
			(start -0.747014 4.310126)
			(end -0.747014 -0.78994)
			(stroke
				(width 0.1)
				(type default)
			)
			(layer "F.Fab")
		)
		(fp_line
			(start 2.853182 -0.78994)
			(end 2.853182 4.310126)
			(stroke
				(width 0.1)
				(type default)
			)
			(layer "F.Fab")
		)
		(fp_line
			(start 2.853182 4.310126)
			(end -0.747014 4.310126)
			(stroke
				(width 0.1)
				(type default)
			)
			(layer "F.Fab")
		)
		(fp_circle
			(center -1.238504 -0.803148)
			(end -1.111504 -0.803148)
			(stroke
				(width 0.254)
				(type default)
			)
			(fill no)
			(layer "F.Fab")
		)
		(pad "1" smd rect
			(at 0 0)
			(size 0.3302 0.3302)
			(layers "F.Cu" "F.Mask" "F.Paste")
			(net "VR_P3V3_STBY_UGATE")
		)
		(pad "2" smd rect
			(at 1.366774 0.002032)
			(size 1.8034 0.508)
			(layers "F.Cu" "F.Mask" "F.Paste")
			(net "VR_FET_SW_P12V_STBY_P3V3_STBY")
		)
		(pad "3" smd custom
			(at 1.053084 2.19202)
			(size 0.56515 0.56515)
			(layers "F.Cu" "F.Mask" "F.Paste")
			(net "GND")
			(options
				(clearance outline)
				(anchor circle)
			)
			(primitives
				(gr_poly
					(pts
						(xy -1.2065 0.3937) (xy -1.2065 -1.1303) (xy 1.2065 -1.1303) (xy 1.2065 1.1303) (xy -0.5969 1.1303)
						(xy -0.5969 0.3937)
					)
					(width 0)
					(fill yes)
				)
			)
		)
		(pad "4" smd rect
			(at 0 3.047238)
			(size 0.3302 0.3302)
			(layers "F.Cu" "F.Mask" "F.Paste")
			(net "VR_P3V3_STBY_LGATE")
		)
		(pad "5" smd rect
			(at 1.053084 4.02463)
			(size 3.5052 0.508)
			(layers "F.Cu" "F.Mask" "F.Paste")
			(net "VR_P3V3_STBY_PHASE")
		)
	)
	(footprint ""
		(layer "F.Cu")
		(at 449.69938 -34.7345 90)
		(property "Reference" "R25W9"
			(at 0 0 90)
			(layer "F.SilkS")
			(hide yes)
			(effects
				(font
					(size 1.27 1.27)
				)
			)
		)
		(property "Value" "*"
			(at 0.064008 -4.108196 90)
			(unlocked yes)
			(layer "F.Fab")
			(hide yes)
			(effects
				(font
					(size 1.27 1.016)
					(thickness 0.1524)
				)
			)
		)
		(property "Device Type" "120R2F-GP_RCL_GP-120R2F-GP,64.A"
			(at 0.064008 -5.632196 90)
			(unlocked yes)
			(layer "F.Fab")
			(hide yes)
			(effects
				(font
					(size 1.27 1.016)
					(thickness 0.1524)
				)
			)
		)
		(duplicate_pad_numbers_are_jumpers no)
		(fp_line
			(start 0.508 -0.9398)
			(end -0.508 -0.9398)
			(stroke
				(width 0.1524)
				(type default)
			)
			(layer "F.SilkS")
		)
		(fp_line
			(start -0.508 -0.9398)
			(end -0.508 0.9398)
			(stroke
				(width 0.1524)
				(type default)
			)
			(layer "F.SilkS")
		)
		(fp_rect
			(start -0.508 0.9398)
			(end 0.508 -0.9398)
			(stroke
				(width 0)
				(type default)
			)
			(fill no)
			(layer "F.CrtYd")
		)
		(fp_rect
			(start -0.508 0.9398)
			(end 0.508 -0.9398)
			(stroke
				(width 0)
				(type default)
			)
			(fill no)
			(layer "F.Fab")
		)
		(pad "1" smd custom
			(at 0 -0.4445 90)
			(size 0.1397 0.1397)
			(layers "F.Cu" "F.Mask" "F.Paste")
			(net "GND")
			(options
				(clearance outline)
				(anchor circle)
			)
			(primitives
				(gr_poly
					(pts
						(arc
							(start -0.1778 -0.2794)
							(mid -0.249642 -0.249642)
							(end -0.2794 -0.1778)
						)
						(arc
							(start -0.2794 0.1778)
							(mid -0.249642 0.249642)
							(end -0.1778 0.2794)
						)
						(arc
							(start 0.1778 0.2794)
							(mid 0.249642 0.249642)
							(end 0.2794 0.1778)
						)
						(arc
							(start 0.2794 -0.1778)
							(mid 0.249642 -0.249642)
							(end 0.1778 -0.2794)
						)
					)
					(width 0)
					(fill yes)
				)
			)
		)
		(pad "2" smd custom
			(at 0 0.4445 90)
			(size 0.1397 0.1397)
			(layers "F.Cu" "F.Mask" "F.Paste")
			(net "BMC_M_BA0")
			(options
				(clearance outline)
				(anchor circle)
			)
			(primitives
				(gr_poly
					(pts
						(arc
							(start -0.1778 -0.2794)
							(mid -0.249642 -0.249642)
							(end -0.2794 -0.1778)
						)
						(arc
							(start -0.2794 0.1778)
							(mid -0.249642 0.249642)
							(end -0.1778 0.2794)
						)
						(arc
							(start 0.1778 0.2794)
							(mid 0.249642 0.249642)
							(end 0.2794 0.1778)
						)
						(arc
							(start 0.2794 -0.1778)
							(mid 0.249642 -0.249642)
							(end 0.1778 -0.2794)
						)
					)
					(width 0)
					(fill yes)
				)
			)
		)
	)
	(footprint ""
		(layer "F.Cu")
		(at 265.901424 -68.412614 180)
		(property "Reference" "C5D56"
			(at 0 0 180)
			(layer "F.SilkS")
			(hide yes)
			(effects
				(font
					(size 1.27 1.27)
				)
			)
		)
		(property "Value" ""
			(at 0 0 180)
			(layer "F.Fab")
			(effects
				(font
					(size 1.27 1.27)
				)
			)
		)
		(duplicate_pad_numbers_are_jumpers no)
		(fp_poly
			(pts
				(xy -0.4953 -0.2032) (xy 0.4953 -0.2032) (xy 0.4953 1.6002) (xy -0.4953 1.6002)
			)
			(stroke
				(width 0)
				(type default)
			)
			(fill no)
			(layer "F.CrtYd")
		)
		(fp_line
			(start 0.4953 1.6002)
			(end -0.4953 1.6002)
			(stroke
				(width 0.1)
				(type default)
			)
			(layer "F.Fab")
		)
		(fp_line
			(start 0.4953 -0.2032)
			(end 0.4953 1.6002)
			(stroke
				(width 0.1)
				(type default)
			)
			(layer "F.Fab")
		)
		(fp_line
			(start -0.4953 1.6002)
			(end -0.4953 -0.2032)
			(stroke
				(width 0.1)
				(type default)
			)
			(layer "F.Fab")
		)
		(fp_line
			(start -0.4953 -0.2032)
			(end 0.4953 -0.2032)
			(stroke
				(width 0.1)
				(type default)
			)
			(layer "F.Fab")
		)
		(pad "1" smd rect
			(at 0 0 180)
			(size 0.762 0.889)
			(layers "F.Cu" "F.Mask" "F.Paste")
			(net "PVDDQ_ABC")
		)
		(pad "2" smd rect
			(at 0 1.397 180)
			(size 0.762 0.889)
			(layers "F.Cu" "F.Mask" "F.Paste")
			(net "GND")
		)
		(zone
			(layer "F.Cu")
			(hatch none 0.5)
			(connect_pads
				(clearance 0)
			)
			(min_thickness 0.25)
			(keepout
				(tracks not_allowed)
				(vias allowed)
				(pads allowed)
				(copperpour not_allowed)
				(footprints allowed)
			)
			(placement
				(enabled no)
				(sheetname "")
			)
			(fill
				(thermal_gap 0.5)
				(thermal_bridge_width 0.5)
				(island_removal_mode 0)
			)
			(polygon
				(pts
					(xy 266.282424 -68.857114) (xy 265.520424 -68.857114) (xy 265.520424 -69.365114) (xy 266.282424 -69.365114)
				)
			)
		)
	)
	(footprint ""
		(layer "F.Cu")
		(at 408.728926 -115.521486 -90)
		(property "Reference" "R8B23"
			(at 0 0 270)
			(layer "F.SilkS")
			(hide yes)
			(effects
				(font
					(size 1.27 1.27)
				)
			)
		)
		(property "Value" ""
			(at 0 0 270)
			(layer "F.Fab")
			(effects
				(font
					(size 1.27 1.27)
				)
			)
		)
		(duplicate_pad_numbers_are_jumpers no)
		(fp_poly
			(pts
				(xy -0.2794 -0.1016) (xy 0.2794 -0.1016) (xy 0.2794 0.9906) (xy -0.2794 0.9906)
			)
			(stroke
				(width 0)
				(type default)
			)
			(fill no)
			(layer "F.CrtYd")
		)
		(fp_line
			(start -0.2794 0.9906)
			(end 0.2794 0.9906)
			(stroke
				(width 0.1)
				(type default)
			)
			(layer "F.Fab")
		)
		(fp_line
			(start 0.2794 0.9906)
			(end 0.2794 -0.1016)
			(stroke
				(width 0.1)
				(type default)
			)
			(layer "F.Fab")
		)
		(fp_line
			(start -0.2794 -0.1016)
			(end -0.2794 0.9906)
			(stroke
				(width 0.1)
				(type default)
			)
			(layer "F.Fab")
		)
		(fp_line
			(start 0.2794 -0.1016)
			(end -0.2794 -0.1016)
			(stroke
				(width 0.1)
				(type default)
			)
			(layer "F.Fab")
		)
		(pad "1" smd rect
			(at 0 0 270)
			(size 0.508 0.508)
			(layers "F.Cu" "F.Mask" "F.Paste")
			(net "P3V3_STBY")
		)
		(pad "2" smd rect
			(at 0 0.889 270)
			(size 0.508 0.508)
			(layers "F.Cu" "F.Mask" "F.Paste")
			(net "FM_XRC_PRESENT_N")
		)
		(zone
			(layer "F.Cu")
			(hatch none 0.5)
			(connect_pads
				(clearance 0)
			)
			(min_thickness 0.25)
			(keepout
				(tracks not_allowed)
				(vias allowed)
				(pads allowed)
				(copperpour not_allowed)
				(footprints allowed)
			)
			(placement
				(enabled no)
				(sheetname "")
			)
			(fill
				(thermal_gap 0.5)
				(thermal_bridge_width 0.5)
				(island_removal_mode 0)
			)
			(polygon
				(pts
					(xy 408.093926 -115.775486) (xy 408.093926 -115.267486) (xy 408.474926 -115.267486) (xy 408.474926 -115.775486)
				)
			)
		)
		(zone
			(layer "F.Cu")
			(hatch none 0.5)
			(connect_pads
				(clearance 0)
			)
			(min_thickness 0.25)
			(keepout
				(tracks allowed)
				(vias not_allowed)
				(pads allowed)
				(copperpour not_allowed)
				(footprints allowed)
			)
			(placement
				(enabled no)
				(sheetname "")
			)
			(fill
				(thermal_gap 0.5)
				(thermal_bridge_width 0.5)
				(island_removal_mode 0)
			)
			(polygon
				(pts
					(xy 408.474926 -115.775486) (xy 408.474926 -115.267486) (xy 408.093926 -115.267486) (xy 408.093926 -115.775486)
				)
			)
		)
	)
	(footprint ""
		(layer "F.Cu")
		(at 453.898 -36.449)
		(property "Reference" "DS9E1"
			(at 0 0 0)
			(layer "F.SilkS")
			(hide yes)
			(effects
				(font
					(size 1.27 1.27)
				)
			)
		)
		(property "Value" ""
			(at 0 0 0)
			(layer "F.Fab")
			(effects
				(font
					(size 1.27 1.27)
				)
			)
		)
		(duplicate_pad_numbers_are_jumpers no)
		(fp_line
			(start -1.985772 0.486918)
			(end -1.50495 0.486918)
			(stroke
				(width 0.1524)
				(type default)
			)
			(layer "F.SilkS")
		)
		(fp_line
			(start -1.985772 1.319784)
			(end -1.024128 1.319784)
			(stroke
				(width 0.1524)
				(type default)
			)
			(layer "F.SilkS")
		)
		(fp_line
			(start -1.50495 -0.424688)
			(end -1.50495 0.486918)
			(stroke
				(width 0.1524)
				(type default)
			)
			(layer "F.SilkS")
		)
		(fp_line
			(start -1.50495 0.486918)
			(end -1.024128 0.486918)
			(stroke
				(width 0.1524)
				(type default)
			)
			(layer "F.SilkS")
		)
		(fp_line
			(start -1.50495 1.319784)
			(end -1.985772 0.486918)
			(stroke
				(width 0.1524)
				(type default)
			)
			(layer "F.SilkS")
		)
		(fp_line
			(start -1.50495 2.443226)
			(end -1.50495 1.319784)
			(stroke
				(width 0.1524)
				(type default)
			)
			(layer "F.SilkS")
		)
		(fp_line
			(start -1.024128 0.486918)
			(end -1.50495 1.319784)
			(stroke
				(width 0.1524)
				(type default)
			)
			(layer "F.SilkS")
		)
		(fp_poly
			(pts
				(xy 0.6223 2.032) (xy -0.6223 2.032) (xy -0.6223 0.0254) (xy 0.6223 0.0254)
			)
			(stroke
				(width 0)
				(type default)
			)
			(fill no)
			(layer "F.CrtYd")
		)
		(fp_line
			(start -1.985772 0.486918)
			(end -1.024128 0.486918)
			(stroke
				(width 0.1)
				(type default)
			)
			(layer "F.Fab")
		)
		(fp_line
			(start -1.985772 1.319784)
			(end -1.024128 1.319784)
			(stroke
				(width 0.1)
				(type default)
			)
			(layer "F.Fab")
		)
		(fp_line
			(start -1.50495 0.486918)
			(end -1.50495 -0.424688)
			(stroke
				(width 0.1)
				(type default)
			)
			(layer "F.Fab")
		)
		(fp_line
			(start -1.50495 1.319784)
			(end -1.985772 0.486918)
			(stroke
				(width 0.1)
				(type default)
			)
			(layer "F.Fab")
		)
		(fp_line
			(start -1.50495 1.319784)
			(end -1.50495 2.443226)
			(stroke
				(width 0.1)
				(type default)
			)
			(layer "F.Fab")
		)
		(fp_line
			(start -1.024128 0.486918)
			(end -1.50495 1.319784)
			(stroke
				(width 0.1)
				(type default)
			)
			(layer "F.Fab")
		)
		(fp_line
			(start -0.6223 0.0254)
			(end 0.6223 0.0254)
			(stroke
				(width 0.1)
				(type default)
			)
			(layer "F.Fab")
		)
		(fp_line
			(start -0.6223 2.032)
			(end -0.6223 0.0254)
			(stroke
				(width 0.1)
				(type default)
			)
			(layer "F.Fab")
		)
		(fp_line
			(start 0.6223 0.0254)
			(end 0.6223 2.032)
			(stroke
				(width 0.1)
				(type default)
			)
			(layer "F.Fab")
		)
		(fp_line
			(start 0.6223 2.032)
			(end -0.6223 2.032)
			(stroke
				(width 0.1)
				(type default)
			)
			(layer "F.Fab")
		)
		(pad "1" smd rect
			(at 0 0)
			(size 1.27 1.27)
			(layers "F.Cu" "F.Mask" "F.Paste")
			(net "FM_HEARTBEAT_LED_A")
		)
		(pad "2" smd rect
			(at 0 2.032)
			(size 1.27 1.27)
			(layers "F.Cu" "F.Mask" "F.Paste")
			(net "FM_HEARTBEAT_LED_K")
		)
		(zone
			(layer "F.Cu")
			(hatch none 0.5)
			(connect_pads
				(clearance 0)
			)
			(min_thickness 0.25)
			(keepout
				(tracks not_allowed)
				(vias allowed)
				(pads allowed)
				(copperpour not_allowed)
				(footprints allowed)
			)
			(placement
				(enabled no)
				(sheetname "")
			)
			(fill
				(thermal_gap 0.5)
				(thermal_bridge_width 0.5)
				(island_removal_mode 0)
			)
			(polygon
				(pts
					(xy 453.263 -35.052) (xy 454.533 -35.052) (xy 454.533 -35.814) (xy 453.263 -35.814)
				)
			)
		)
		(zone
			(layer "F.Cu")
			(hatch none 0.5)
			(connect_pads
				(clearance 0)
			)
			(min_thickness 0.25)
			(keepout
				(tracks allowed)
				(vias not_allowed)
				(pads allowed)
				(copperpour not_allowed)
				(footprints allowed)
			)
			(placement
				(enabled no)
				(sheetname "")
			)
			(fill
				(thermal_gap 0.5)
				(thermal_bridge_width 0.5)
				(island_removal_mode 0)
			)
			(polygon
				(pts
					(xy 453.263 -35.052) (xy 454.533 -35.052) (xy 454.533 -35.814) (xy 453.263 -35.814)
				)
			)
		)
	)
	(footprint ""
		(layer "F.Cu")
		(at 25.02916 -90.05824 180)
		(property "Reference" "CF9"
			(at 0 0 180)
			(layer "F.SilkS")
			(hide yes)
			(effects
				(font
					(size 1.27 1.27)
				)
			)
		)
		(property "Value" "*"
			(at 1.1811 -2.8194 180)
			(unlocked yes)
			(layer "F.Fab")
			(hide yes)
			(effects
				(font
					(size 1.27 1.016)
					(thickness 0.1524)
				)
			)
		)
		(property "Device Type" "SC22P50V2JN-4GP_SMD-BCG-SC22P5A"
			(at 1.1811 -4.3434 180)
			(unlocked yes)
			(layer "F.Fab")
			(hide yes)
			(effects
				(font
					(size 1.27 1.016)
					(thickness 0.1524)
				)
			)
		)
		(duplicate_pad_numbers_are_jumpers no)
		(fp_rect
			(start -0.4318 0.9525)
			(end 0.4318 -0.9525)
			(stroke
				(width 0)
				(type default)
			)
			(fill no)
			(layer "F.CrtYd")
		)
		(fp_rect
			(start -0.4318 0.9525)
			(end 0.4318 -0.9525)
			(stroke
				(width 0)
				(type default)
			)
			(fill no)
			(layer "F.Fab")
		)
		(pad "1" smd custom
			(at 0 -0.4445 180)
			(size 0.1524 0.1524)
			(layers "F.Cu" "F.Mask" "F.Paste")
			(net "VR_PVCCIN_CPU1_AIREF3")
			(options
				(clearance outline)
				(anchor circle)
			)
			(primitives
				(gr_poly
					(pts
						(arc
							(start 0.3048 -0.2032)
							(mid 0.275042 -0.275042)
							(end 0.2032 -0.3048)
						)
						(arc
							(start -0.2032 -0.3048)
							(mid -0.275042 -0.275042)
							(end -0.3048 -0.2032)
						)
						(arc
							(start -0.3048 0.2032)
							(mid -0.275042 0.275042)
							(end -0.2032 0.3048)
						)
						(arc
							(start 0.2032 0.3048)
							(mid 0.275042 0.275042)
							(end 0.3048 0.2032)
						)
					)
					(width 0)
					(fill yes)
				)
			)
		)
		(pad "2" smd custom
			(at 0 0.4445 180)
			(size 0.1524 0.1524)
			(layers "F.Cu" "F.Mask" "F.Paste")
			(net "ISENSE_PVCCIN_CPU1_PH3_IMON")
			(options
				(clearance outline)
				(anchor circle)
			)
			(primitives
				(gr_poly
					(pts
						(arc
							(start 0.3048 -0.2032)
							(mid 0.275042 -0.275042)
							(end 0.2032 -0.3048)
						)
						(arc
							(start -0.2032 -0.3048)
							(mid -0.275042 -0.275042)
							(end -0.3048 -0.2032)
						)
						(arc
							(start -0.3048 0.2032)
							(mid -0.275042 0.275042)
							(end -0.2032 0.3048)
						)
						(arc
							(start 0.2032 0.3048)
							(mid 0.275042 0.275042)
							(end 0.3048 0.2032)
						)
					)
					(width 0)
					(fill yes)
				)
			)
		)
	)
)
